(kicad_pcb
	(version 20241229)
	(generator "pcbnew")
	(generator_version "9.0")
	(general
		(thickness 1.61)
		(legacy_teardrops no)
	)
	(paper "A3")
	(title_block
		(title "RDIMM DDR5 Tester")
		(date "2026-05-21")
		(rev "2.2.0")
		(company "Antmicro")
		(comment 9 "footprints 17-21 of 796")
	)
	(layers
		(0 "F.Cu" signal)
		(4 "In1.Cu" power)
		(6 "In2.Cu" mixed)
		(8 "In3.Cu" power)
		(10 "In4.Cu" mixed)
		(12 "In5.Cu" power)
		(14 "In6.Cu" mixed)
		(16 "In7.Cu" power)
		(18 "In8.Cu" power)
		(20 "In9.Cu" mixed)
		(22 "In10.Cu" power)
		(2 "B.Cu" signal)
		(9 "F.Adhes" user "F.Adhesive")
		(11 "B.Adhes" user "B.Adhesive")
		(13 "F.Paste" user)
		(15 "B.Paste" user)
		(5 "F.SilkS" user "F.Silkscreen")
		(7 "B.SilkS" user "B.Silkscreen")
		(1 "F.Mask" user)
		(3 "B.Mask" user)
		(17 "Dwgs.User" user "User.Drawings")
		(19 "Cmts.User" user "User.Comments")
		(21 "Eco1.User" user "User.Eco1")
		(23 "Eco2.User" user "User.Eco2")
		(25 "Edge.Cuts" user)
		(27 "Margin" user)
		(31 "F.CrtYd" user "F.Courtyard")
		(29 "B.CrtYd" user "B.Courtyard")
		(35 "F.Fab" user)
		(33 "B.Fab" user)
	)
	(footprint "antmicro-footprints:R_0402_1005Metric"
		(layer "F.Cu")
		(at 134.176843 161.831328)
		(descr "Resistor SMD 0402")
		(tags "resistor SMD 0402")
		(property "Reference" "R44"
			(at 0.823157 0.468672 0)
			(layer "F.SilkS")
			(effects
				(font
					(size 0.7 0.7)
					(thickness 0.15)
				)
				(justify left bottom)
			)
		)
		(property "Value" "R_12k_0402"
			(at -1.011843 1.772047 0)
			(layer "F.Fab")
			(effects
				(font
					(size 0.7 0.7)
					(thickness 0.15)
				)
				(justify left bottom)
			)
		)
		(property "Datasheet" "https://www.bourns.com/docs/product-datasheets/cr.pdf"
			(at 0 0 0)
			(layer "F.Fab")
			(hide yes)
			(effects
				(font
					(size 1.27 1.27)
					(thickness 0.15)
				)
			)
		)
		(property "Manufacturer" "Bourns"
			(at 0 0 0)
			(unlocked yes)
			(layer "F.Fab")
			(hide yes)
			(effects
				(font
					(size 1 1)
					(thickness 0.15)
				)
			)
		)
		(property "MPN" "CR0402-FX-1202GLF"
			(at 0 0 0)
			(unlocked yes)
			(layer "F.Fab")
			(hide yes)
			(effects
				(font
					(size 1 1)
					(thickness 0.15)
				)
			)
		)
		(property "Val" "12k"
			(at 0 0 0)
			(unlocked yes)
			(layer "F.Fab")
			(hide yes)
			(effects
				(font
					(size 1 1)
					(thickness 0.15)
				)
			)
		)
		(property "License" "Apache-2.0"
			(at 0 0 0)
			(unlocked yes)
			(layer "F.Fab")
			(hide yes)
			(effects
				(font
					(size 1 1)
					(thickness 0.15)
				)
			)
		)
		(property "Author" "Antmicro"
			(at 0 0 0)
			(unlocked yes)
			(layer "F.Fab")
			(hide yes)
			(effects
				(font
					(size 1 1)
					(thickness 0.15)
				)
			)
		)
		(property "Tolerance" "1%"
			(at 0 0 0)
			(unlocked yes)
			(layer "F.Fab")
			(hide yes)
			(effects
				(font
					(size 1 1)
					(thickness 0.15)
				)
			)
		)
		(sheetname "/Debug FTDI + VNA/")
		(sheetfile "debug-ftdi.kicad_sch")
		(attr smd)
		(fp_rect
			(start -0.925 -0.47)
			(end 0.925 0.47)
			(stroke
				(width 0.05)
				(type default)
			)
			(fill no)
			(layer "F.CrtYd")
		)
		(fp_rect
			(start -0.5 -0.25)
			(end 0.5 0.25)
			(stroke
				(width 0.15)
				(type solid)
			)
			(fill no)
			(layer "F.Fab")
		)
		(fp_text user "License: Apache-2.0"
			(at -0.95 5.169 0)
			(layer "F.Fab")
			(effects
				(font
					(size 0.7 0.7)
					(thickness 0.15)
				)
				(justify left bottom)
			)
		)
		(fp_text user "Author: Antmicro"
			(at -0.95 4.169 0)
			(layer "F.Fab")
			(effects
				(font
					(size 0.7 0.7)
					(thickness 0.15)
				)
				(justify left bottom)
			)
		)
		(fp_text user "${REFERENCE}"
			(at -0.95 3.168 0)
			(layer "F.Fab")
			(effects
				(font
					(size 0.7 0.7)
					(thickness 0.15)
				)
				(justify left bottom)
			)
		)
		(pad "1" smd roundrect
			(at -0.48 0)
			(size 0.59 0.64)
			(layers "F.Cu" "F.Mask" "F.Paste")
			(roundrect_rratio 0.25)
			(net 1 "GND")
			(pintype "passive")
		)
		(pad "2" smd roundrect
			(at 0.48 0)
			(size 0.59 0.64)
			(layers "F.Cu" "F.Mask" "F.Paste")
			(roundrect_rratio 0.25)
			(net 293 "Net-(U6-REF)")
			(pintype "passive")
		)
	)
	(footprint "antmicro-footprints:C_0402_1005Metric"
		(layer "F.Cu")
		(at 133.815 164.485 -90)
		(descr "Capacitor SMD 0402")
		(tags "capacitor SMD 0402")
		(property "Reference" "C110"
			(at -0.335 -2.285 90)
			(layer "F.SilkS")
			(effects
				(font
					(size 0.7 0.7)
					(thickness 0.15)
				)
				(justify right bottom)
			)
		)
		(property "Value" "C_100n_0402"
			(at -1.022927 2.155213 90)
			(layer "F.Fab")
			(effects
				(font
					(size 0.7 0.7)
					(thickness 0.15)
				)
				(justify right bottom)
			)
		)
		(property "Datasheet" "https://www.murata.com/products/productdetail?partno=GRM155R61H104KE14%23"
			(at 0 0 270)
			(layer "F.Fab")
			(hide yes)
			(effects
				(font
					(size 1.27 1.27)
					(thickness 0.15)
				)
			)
		)
		(property "Manufacturer" "Murata"
			(at 0 0 270)
			(unlocked yes)
			(layer "F.Fab")
			(hide yes)
			(effects
				(font
					(size 1 1)
					(thickness 0.15)
				)
			)
		)
		(property "MPN" "GRM155R61H104KE14D"
			(at 0 0 270)
			(unlocked yes)
			(layer "F.Fab")
			(hide yes)
			(effects
				(font
					(size 1 1)
					(thickness 0.15)
				)
			)
		)
		(property "Val" "100n"
			(at 0 0 270)
			(unlocked yes)
			(layer "F.Fab")
			(hide yes)
			(effects
				(font
					(size 1 1)
					(thickness 0.15)
				)
			)
		)
		(property "License" "Apache-2.0"
			(at 0 0 270)
			(unlocked yes)
			(layer "F.Fab")
			(hide yes)
			(effects
				(font
					(size 1 1)
					(thickness 0.15)
				)
			)
		)
		(property "Author" "Antmicro"
			(at 0 0 270)
			(unlocked yes)
			(layer "F.Fab")
			(hide yes)
			(effects
				(font
					(size 1 1)
					(thickness 0.15)
				)
			)
		)
		(property "Voltage" "50V"
			(at 0 0 270)
			(unlocked yes)
			(layer "F.Fab")
			(hide yes)
			(effects
				(font
					(size 1 1)
					(thickness 0.15)
				)
			)
		)
		(property "Dielectric" "X5R"
			(at 0 0 270)
			(unlocked yes)
			(layer "F.Fab")
			(hide yes)
			(effects
				(font
					(size 1 1)
					(thickness 0.15)
				)
			)
		)
		(sheetname "/Debug FTDI + VNA/")
		(sheetfile "debug-ftdi.kicad_sch")
		(attr smd)
		(fp_rect
			(start -0.925 -0.47)
			(end 0.925 0.47)
			(stroke
				(width 0.05)
				(type default)
			)
			(fill no)
			(layer "F.CrtYd")
		)
		(fp_line
			(start -0.494 0.248)
			(end -0.494 -0.25)
			(stroke
				(width 0.15)
				(type solid)
			)
			(layer "F.Fab")
		)
		(fp_line
			(start 0.504 0.248)
			(end -0.494 0.248)
			(stroke
				(width 0.15)
				(type solid)
			)
			(layer "F.Fab")
		)
		(fp_line
			(start -0.494 -0.25)
			(end 0.504 -0.25)
			(stroke
				(width 0.15)
				(type solid)
			)
			(layer "F.Fab")
		)
		(fp_line
			(start 0.504 -0.25)
			(end 0.504 0.248)
			(stroke
				(width 0.15)
				(type solid)
			)
			(layer "F.Fab")
		)
		(fp_text user "Author: Antmicro"
			(at -0.939 3.399 270)
			(layer "F.Fab")
			(effects
				(font
					(size 0.7 0.7)
					(thickness 0.15)
				)
				(justify left bottom)
			)
		)
		(fp_text user "License: Apache-2.0"
			(at -0.939 5.799 270)
			(layer "F.Fab")
			(effects
				(font
					(size 0.7 0.7)
					(thickness 0.15)
				)
				(justify left bottom)
			)
		)
		(fp_text user "${REFERENCE}"
			(at -0.939 4.599 270)
			(layer "F.Fab")
			(effects
				(font
					(size 0.7 0.7)
					(thickness 0.15)
				)
				(justify left bottom)
			)
		)
		(pad "1" smd roundrect
			(at -0.48 0 270)
			(size 0.59 0.64)
			(layers "F.Cu" "F.Mask" "F.Paste")
			(roundrect_rratio 0.25)
			(net 3 "/Debug FTDI + VNA/FTDI_VPLL")
			(pintype "passive")
		)
		(pad "2" smd roundrect
			(at 0.48 0 270)
			(size 0.59 0.64)
			(layers "F.Cu" "F.Mask" "F.Paste")
			(roundrect_rratio 0.25)
			(net 1 "GND")
			(pintype "passive")
		)
	)
	(footprint "antmicro-footprints:C_0402_1005Metric"
		(layer "F.Cu")
		(at 134.8135 164.484 -90)
		(descr "Capacitor SMD 0402")
		(tags "capacitor SMD 0402")
		(property "Reference" "C114"
			(at -0.335 -2.285 90)
			(layer "F.SilkS")
			(effects
				(font
					(size 0.7 0.7)
					(thickness 0.15)
				)
				(justify right bottom)
			)
		)
		(property "Value" "C_4u7_0402"
			(at -1.022927 2.155213 90)
			(layer "F.Fab")
			(effects
				(font
					(size 0.7 0.7)
					(thickness 0.15)
				)
				(justify right bottom)
			)
		)
		(property "Datasheet" "https://www.murata.com/products/productdetail?partno=GRM155R61A475MEAA%23"
			(at 0 0 270)
			(layer "F.Fab")
			(hide yes)
			(effects
				(font
					(size 1.27 1.27)
					(thickness 0.15)
				)
			)
		)
		(property "Manufacturer" "Murata"
			(at 0 0 270)
			(unlocked yes)
			(layer "F.Fab")
			(hide yes)
			(effects
				(font
					(size 1 1)
					(thickness 0.15)
				)
			)
		)
		(property "MPN" "GRM155R61A475MEAAD"
			(at 0 0 270)
			(unlocked yes)
			(layer "F.Fab")
			(hide yes)
			(effects
				(font
					(size 1 1)
					(thickness 0.15)
				)
			)
		)
		(property "Val" "4u7"
			(at 0 0 270)
			(unlocked yes)
			(layer "F.Fab")
			(hide yes)
			(effects
				(font
					(size 1 1)
					(thickness 0.15)
				)
			)
		)
		(property "License" "Apache-2.0"
			(at 0 0 270)
			(unlocked yes)
			(layer "F.Fab")
			(hide yes)
			(effects
				(font
					(size 1 1)
					(thickness 0.15)
				)
			)
		)
		(property "Author" "Antmicro"
			(at 0 0 270)
			(unlocked yes)
			(layer "F.Fab")
			(hide yes)
			(effects
				(font
					(size 1 1)
					(thickness 0.15)
				)
			)
		)
		(property "Voltage" ""
			(at 0 0 270)
			(unlocked yes)
			(layer "F.Fab")
			(hide yes)
			(effects
				(font
					(size 1 1)
					(thickness 0.15)
				)
			)
		)
		(property "Dielectric" ""
			(at 0 0 270)
			(unlocked yes)
			(layer "F.Fab")
			(hide yes)
			(effects
				(font
					(size 1 1)
					(thickness 0.15)
				)
			)
		)
		(sheetname "/Debug FTDI + VNA/")
		(sheetfile "debug-ftdi.kicad_sch")
		(attr smd)
		(fp_rect
			(start -0.925 -0.47)
			(end 0.925 0.47)
			(stroke
				(width 0.05)
				(type default)
			)
			(fill no)
			(layer "F.CrtYd")
		)
		(fp_line
			(start -0.494 0.248)
			(end -0.494 -0.25)
			(stroke
				(width 0.15)
				(type solid)
			)
			(layer "F.Fab")
		)
		(fp_line
			(start 0.504 0.248)
			(end -0.494 0.248)
			(stroke
				(width 0.15)
				(type solid)
			)
			(layer "F.Fab")
		)
		(fp_line
			(start -0.494 -0.25)
			(end 0.504 -0.25)
			(stroke
				(width 0.15)
				(type solid)
			)
			(layer "F.Fab")
		)
		(fp_line
			(start 0.504 -0.25)
			(end 0.504 0.248)
			(stroke
				(width 0.15)
				(type solid)
			)
			(layer "F.Fab")
		)
		(fp_text user "Author: Antmicro"
			(at -0.939 3.399 270)
			(layer "F.Fab")
			(effects
				(font
					(size 0.7 0.7)
					(thickness 0.15)
				)
				(justify left bottom)
			)
		)
		(fp_text user "License: Apache-2.0"
			(at -0.939 5.799 270)
			(layer "F.Fab")
			(effects
				(font
					(size 0.7 0.7)
					(thickness 0.15)
				)
				(justify left bottom)
			)
		)
		(fp_text user "${REFERENCE}"
			(at -0.939 4.599 270)
			(layer "F.Fab")
			(effects
				(font
					(size 0.7 0.7)
					(thickness 0.15)
				)
				(justify left bottom)
			)
		)
		(pad "1" smd roundrect
			(at -0.48 0 270)
			(size 0.59 0.64)
			(layers "F.Cu" "F.Mask" "F.Paste")
			(roundrect_rratio 0.25)
			(net 3 "/Debug FTDI + VNA/FTDI_VPLL")
			(pintype "passive")
		)
		(pad "2" smd roundrect
			(at 0.48 0 270)
			(size 0.59 0.64)
			(layers "F.Cu" "F.Mask" "F.Paste")
			(roundrect_rratio 0.25)
			(net 1 "GND")
			(pintype "passive")
		)
	)
	(footprint "antmicro-footprints:FB_0603_1608Metric"
		(layer "F.Cu")
		(at 132.435 164.984 90)
		(property "Reference" "FB1"
			(at -3.616 0.365 90)
			(layer "F.SilkS")
			(effects
				(font
					(size 0.7 0.7)
					(thickness 0.15)
				)
				(justify left bottom)
			)
		)
		(property "Value" "FB_600Z_0.5A_Murata-BLM18AG_0603"
			(at 0 1.5 90)
			(layer "F.Fab")
			(effects
				(font
					(size 0.7 0.7)
					(thickness 0.15)
				)
				(justify left bottom)
			)
		)
		(property "Datasheet" "https://www.murata.com/en-us/products/productdata/8796738650142/ENFA0003.pdf"
			(at 0 0 90)
			(layer "F.Fab")
			(hide yes)
			(effects
				(font
					(size 1.27 1.27)
					(thickness 0.15)
				)
			)
		)
		(property "Val" "600Z/0.5A"
			(at 0 0 90)
			(unlocked yes)
			(layer "F.Fab")
			(hide yes)
			(effects
				(font
					(size 1 1)
					(thickness 0.15)
				)
			)
		)
		(property "MPN" "BLM18AG601SN1D"
			(at 0 0 90)
			(unlocked yes)
			(layer "F.Fab")
			(hide yes)
			(effects
				(font
					(size 1 1)
					(thickness 0.15)
				)
			)
		)
		(property "Manufacturer" "Murata"
			(at 0 0 90)
			(unlocked yes)
			(layer "F.Fab")
			(hide yes)
			(effects
				(font
					(size 1 1)
					(thickness 0.15)
				)
			)
		)
		(property "Author" "Antmicro"
			(at 0 0 90)
			(unlocked yes)
			(layer "F.Fab")
			(hide yes)
			(effects
				(font
					(size 1 1)
					(thickness 0.15)
				)
			)
		)
		(property "License" "Apache-2.0"
			(at 0 0 90)
			(unlocked yes)
			(layer "F.Fab")
			(hide yes)
			(effects
				(font
					(size 1 1)
					(thickness 0.15)
				)
			)
		)
		(sheetname "/Debug FTDI + VNA/")
		(sheetfile "debug-ftdi.kicad_sch")
		(attr smd)
		(fp_line
			(start -0.15 -0.4)
			(end 0.15 -0.4)
			(stroke
				(width 0.15)
				(type solid)
			)
			(layer "F.SilkS")
		)
		(fp_line
			(start -0.15 0.4)
			(end 0.15 0.4)
			(stroke
				(width 0.15)
				(type solid)
			)
			(layer "F.SilkS")
		)
		(fp_rect
			(start -1.25 -0.65)
			(end 1.25 0.65)
			(stroke
				(width 0.05)
				(type solid)
			)
			(fill no)
			(layer "F.CrtYd")
		)
		(fp_line
			(start 0.8 -0.408)
			(end -0.803 -0.408)
			(stroke
				(width 0.15)
				(type solid)
			)
			(layer "F.Fab")
		)
		(fp_line
			(start 0.8 -0.408)
			(end 0.8 0.406)
			(stroke
				(width 0.15)
				(type solid)
			)
			(layer "F.Fab")
		)
		(fp_line
			(start 0.8 0.406)
			(end -0.803 0.406)
			(stroke
				(width 0.15)
				(type solid)
			)
			(layer "F.Fab")
		)
		(fp_line
			(start -0.803 0.406)
			(end -0.803 -0.408)
			(stroke
				(width 0.15)
				(type solid)
			)
			(layer "F.Fab")
		)
		(fp_text user "${REFERENCE}"
			(at -1.653 4.6 90)
			(layer "F.Fab")
			(effects
				(font
					(size 0.7 0.7)
					(thickness 0.15)
				)
				(justify left bottom)
			)
		)
		(fp_text user "Author: Antmicro"
			(at -1.653 3.162 90)
			(layer "F.Fab")
			(effects
				(font
					(size 0.7 0.7)
					(thickness 0.15)
				)
				(justify left bottom)
			)
		)
		(fp_text user "License: Apache-2.0"
			(at -1.653 5.9 90)
			(layer "F.Fab")
			(effects
				(font
					(size 0.7 0.7)
					(thickness 0.15)
				)
				(justify left bottom)
			)
		)
		(pad "1" smd roundrect
			(at -0.7 0 90)
			(size 0.8 1)
			(layers "F.Cu" "F.Mask" "F.Paste")
			(roundrect_rratio 0.2)
			(net 6 "/Debug FTDI + VNA/FTDI_3V3")
			(pintype "passive")
		)
		(pad "2" smd roundrect
			(at 0.7 0 90)
			(size 0.8 1)
			(layers "F.Cu" "F.Mask" "F.Paste")
			(roundrect_rratio 0.2)
			(net 3 "/Debug FTDI + VNA/FTDI_VPLL")
			(pintype "passive")
		)
	)
	(footprint "antmicro-footprints:C_0402_1005Metric"
		(layer "F.Cu")
		(at 132.648 154.624 -90)
		(descr "Capacitor SMD 0402")
		(tags "capacitor SMD 0402")
		(property "Reference" "C117"
			(at -3.724 -0.452 90)
			(layer "F.SilkS")
			(effects
				(font
					(size 0.7 0.7)
					(thickness 0.15)
				)
				(justify right bottom)
			)
		)
		(property "Value" "C_18p_0402"
			(at -1.022927 2.155213 90)
			(layer "F.Fab")
			(effects
				(font
					(size 0.7 0.7)
					(thickness 0.15)
				)
				(justify right bottom)
			)
		)
		(property "Datasheet" "https://product.samsungsem.com/mlcc/CL05C180JB51PN.do"
			(at 0 0 270)
			(layer "F.Fab")
			(hide yes)
			(effects
				(font
					(size 1.27 1.27)
					(thickness 0.15)
				)
			)
		)
		(property "Manufacturer" "Samsung Electro-Mechanics"
			(at 0 0 270)
			(unlocked yes)
			(layer "F.Fab")
			(hide yes)
			(effects
				(font
					(size 1 1)
					(thickness 0.15)
				)
			)
		)
		(property "MPN" "CL05C180JB51PNC"
			(at 0 0 270)
			(unlocked yes)
			(layer "F.Fab")
			(hide yes)
			(effects
				(font
					(size 1 1)
					(thickness 0.15)
				)
			)
		)
		(property "Val" "18p"
			(at 0 0 270)
			(unlocked yes)
			(layer "F.Fab")
			(hide yes)
			(effects
				(font
					(size 1 1)
					(thickness 0.15)
				)
			)
		)
		(property "License" "Apache-2.0"
			(at 0 0 270)
			(unlocked yes)
			(layer "F.Fab")
			(hide yes)
			(effects
				(font
					(size 1 1)
					(thickness 0.15)
				)
			)
		)
		(property "Author" "Antmicro"
			(at 0 0 270)
			(unlocked yes)
			(layer "F.Fab")
			(hide yes)
			(effects
				(font
					(size 1 1)
					(thickness 0.15)
				)
			)
		)
		(property "Voltage" ""
			(at 0 0 270)
			(unlocked yes)
			(layer "F.Fab")
			(hide yes)
			(effects
				(font
					(size 1 1)
					(thickness 0.15)
				)
			)
		)
		(property "Dielectric" ""
			(at 0 0 270)
			(unlocked yes)
			(layer "F.Fab")
			(hide yes)
			(effects
				(font
					(size 1 1)
					(thickness 0.15)
				)
			)
		)
		(sheetname "/Debug FTDI + VNA/")
		(sheetfile "debug-ftdi.kicad_sch")
		(attr smd)
		(fp_rect
			(start -0.925 -0.47)
			(end 0.925 0.47)
			(stroke
				(width 0.05)
				(type default)
			)
			(fill no)
			(layer "F.CrtYd")
		)
		(fp_line
			(start -0.494 0.248)
			(end -0.494 -0.25)
			(stroke
				(width 0.15)
				(type solid)
			)
			(layer "F.Fab")
		)
		(fp_line
			(start 0.504 0.248)
			(end -0.494 0.248)
			(stroke
				(width 0.15)
				(type solid)
			)
			(layer "F.Fab")
		)
		(fp_line
			(start -0.494 -0.25)
			(end 0.504 -0.25)
			(stroke
				(width 0.15)
				(type solid)
			)
			(layer "F.Fab")
		)
		(fp_line
			(start 0.504 -0.25)
			(end 0.504 0.248)
			(stroke
				(width 0.15)
				(type solid)
			)
			(layer "F.Fab")
		)
		(fp_text user "License: Apache-2.0"
			(at -0.939 5.799 270)
			(layer "F.Fab")
			(effects
				(font
					(size 0.7 0.7)
					(thickness 0.15)
				)
				(justify left bottom)
			)
		)
		(fp_text user "Author: Antmicro"
			(at -0.939 3.399 270)
			(layer "F.Fab")
			(effects
				(font
					(size 0.7 0.7)
					(thickness 0.15)
				)
				(justify left bottom)
			)
		)
		(fp_text user "${REFERENCE}"
			(at -0.939 4.599 270)
			(layer "F.Fab")
			(effects
				(font
					(size 0.7 0.7)
					(thickness 0.15)
				)
				(justify left bottom)
			)
		)
		(pad "1" smd roundrect
			(at -0.48 0 270)
			(size 0.59 0.64)
			(layers "F.Cu" "F.Mask" "F.Paste")
			(roundrect_rratio 0.25)
			(net 7 "/Debug FTDI + VNA/FTDI_XO")
			(pintype "passive")
		)
		(pad "2" smd roundrect
			(at 0.48 0 270)
			(size 0.59 0.64)
			(layers "F.Cu" "F.Mask" "F.Paste")
			(roundrect_rratio 0.25)
			(net 1 "GND")
			(pintype "passive")
		)
	)
)
